FILE_TYPE = MACRO_DRAWING;
SET COLOR_WIRE YELLOW;
SET COLOR_PROP MONO;
SET COLOR_DOT WHITE;
SET COLOR_ARC YELLOW;
SET COLOR_BODY GREEN;
SET COLOR_NOTE MONO;
SET PROP_DISPLAY VALUE;
SET PAGE_NUMBER P14;
FORCEADD INTEL_CORP_BPAGE..1
(3000 100);
FORCEPROP 1 LAST CUSTOM_TXT_CDS <CURRENT_DESIGN_SHEET> OF <TOTAL_DESIGN_SHEETS>
J 0
(2500 125);
PAINT GREEN (2500 125);
FORCEPROP 1 LAST CUSTOM_TXT_CDS <CON_LAST_MODIFIED>
J 0
(1075 450);
PAINT GREEN (1075 450);
FORCEPROP 2 LAST CUSTOM_TXT_CDS <XR_PAGE_TITLE>
J 0
(-4890 5350);
DISPLAY 0.638298 (-4890 5350);
PAINT PINK (-4890 5350);
DISPLAY INVISIBLE (-4890 5350);
FORCEPROP 1 LAST SCH_ADDRESS3 Santa Clara, CA 95052-8119
J 0
(-975 125);
DISPLAY 0.617021 (-975 125);
PAINT GREEN (-975 125);
FORCEPROP 1 LAST SCH_ADDRESS2 P.O. BOX 58119
J 0
(-975 175);
DISPLAY 0.617021 (-975 175);
PAINT GREEN (-975 175);
FORCEPROP 1 LAST SCH_ADDRESS1 2200 Mission College Blvd.
J 0
(-975 225);
DISPLAY 0.617021 (-975 225);
PAINT GREEN (-975 225);
FORCEPROP 1 LAST SCH_TITLE MCP JTAG BLOCK DIAGRAM
J 0
(-4950 150);
DISPLAY 1.212766 (-4950 150);
PAINT ORANGE (-4950 150);
FORCEPROP 1 LAST SCH_NUMBER H4694802
J 0
(1700 250);
DISPLAY 1.212766 (1700 250);
PAINT YELLOW (1700 250);
FORCEPROP 1 LAST SCH_DEPT BESD
J 1
(-1450 200);
DISPLAY 1.212766 (-1450 200);
PAINT YELLOW (-1450 200);
FORCEPROP 1 LAST SCH_REV 2.420
J 0
(2750 250);
DISPLAY 0.978723 (2750 250);
PAINT YELLOW (2750 250);
FORCEPROP 2 LAST CDS_LIB mstr_symbols
J 0
(3000 100);
PAINT MONO (3000 100);
DISPLAY INVISIBLE (3000 100);
FORCEPROP 2 LAST PAGE_BORDER TRUE
J 0
(-4890 5350);
DISPLAY 0.638298 (-4890 5350);
PAINT PINK (-4890 5350);
DISPLAY INVISIBLE (-4890 5350);
FORCEPROP 1 LAST COMMENT_BODY TRUE
J 0
(3012 112);
DISPLAY 0.468085 (3012 112);
PAINT GREEN (3012 112);
DISPLAY INVISIBLE (3012 112);
FORCEPROP 1 LAST CDS_CON_LAST_MODIFIED Tue Dec 01 11:47:58 2015
J 0
(1575 425);
PAINT ORANGE (1575 425);
DISPLAY INVISIBLE (1575 425);
FORCEPROP 2 LAST CDS_XR_PAGE_TITLE CR-14 : @BASEBOARD_FAB2_LIB.BASEBOARD_FAB2(SCH_1):PAGE14
J 0
(-4890 5350);
DISPLAY 0.638298 (-4890 5350);
PAINT PINK (-4890 5350);
DISPLAY INVISIBLE (-4890 5350);
FORCENOTE
$CDS_IMAGE|14_MCP_JTAG_Topology.jpg|5121|5034
(-1800 2875) 0;
DISPLAY CENTER (-1800 2875);
PAINT MONO (-1800 2875);
QUIT
